# T6G (Grand Teton) — schematic netlist excerpt (pin names and nets, part order shuffled) for the footprints in the layout excerpt that follows; sources: Cadence DE-HDL packaged netlist, KiCad conversion of 04192023_DAF0TMB3IC0_F0TG_MB_C_brd_V02_OCP.brd

C241  Q_CAP  4.7UF 6.3V 20% X6S  pkg 0402  page 323 : A = P0V9_CPU1_RT0_2A ; B = GND
C3917  Q_CAP  22UF 4V 20% X6S  pkg C0402  page 74 : A = PVDDCR_SOC_P1 ; B = GND

(kicad_pcb
	(version 20260206)
	(generator "pcbnew")
	(generator_version "10.0")
	(general
		(thickness 1.6)
		(legacy_teardrops no)
	)
	(paper "A4")
	(title_block
		(title "04192023_DAF0TMB3IC0_F0TG_MB_C_brd_V02_OCP.brd")
		(comment 1 "Grand Teton / footprints 5594-5595 of 8354")
	)
	(layers
		(0 "F.Cu" signal "TOP")
		(4 "In1.Cu" signal "GND")
		(6 "In2.Cu" signal "IN1")
		(8 "In3.Cu" signal "GND1")
		(10 "In4.Cu" signal "IN2")
		(12 "In5.Cu" signal "GND2")
		(14 "In6.Cu" signal "IN3")
		(16 "In7.Cu" signal "GND3")
		(18 "In8.Cu" signal "VCC")
		(20 "In9.Cu" signal "VCC1")
		(22 "In10.Cu" signal "GND4")
		(24 "In11.Cu" signal "IN4")
		(26 "In12.Cu" signal "GND5")
		(28 "In13.Cu" signal "IN5")
		(30 "In14.Cu" signal "GND6")
		(32 "In15.Cu" signal "IN6")
		(34 "In16.Cu" signal "GND7")
		(2 "B.Cu" signal "BOTTOM")
		(9 "F.Adhes" user "F.Adhesive")
		(11 "B.Adhes" user "B.Adhesive")
		(13 "F.Paste" user "Package Geometry/Pastemask Top")
		(15 "B.Paste" user "Package Geometry/Pastemask Bottom")
		(5 "F.SilkS" user "Ref Des/Silkscreen Top")
		(7 "B.SilkS" user "Ref Des/Silkscreen Bottom")
		(1 "F.Mask" user "Board Geometry/Soldermask Top")
		(3 "B.Mask" user "Board Geometry/Soldermask Bottom")
		(17 "Dwgs.User" user "User.Drawings")
		(19 "Cmts.User" user "User.Comments")
		(21 "Eco1.User" user "User.Eco1")
		(23 "Eco2.User" user "User.Eco2")
		(25 "Edge.Cuts" user "Board Geometry/Outline")
		(27 "Margin" user)
		(31 "F.CrtYd" user "Package Geometry/Place Bound Top")
		(29 "B.CrtYd" user "Package Geometry/Place Bound Bottom")
		(35 "F.Fab" user "Ref Des/Assembly Top")
		(33 "B.Fab" user "Ref Des/Assembly Bottom")
	)
	(footprint ""
		(layer "B.Cu")
		(at 60.591192 -390.560052 90)
		(property "Reference" "C241"
			(at 0 0 90)
			(layer "B.SilkS")
			(hide yes)
			(effects
				(font
					(size 1.27 1.27)
				)
				(justify mirror)
			)
		)
		(property "Value" ""
			(at 0 0 90)
			(layer "B.Fab")
			(effects
				(font
					(size 1.27 1.27)
				)
				(justify mirror)
			)
		)
		(duplicate_pad_numbers_are_jumpers no)
		(fp_line
			(start 0.7874 -0.4064)
			(end -0.7874 -0.4064)
			(stroke
				(width 0.1524)
				(type default)
			)
			(layer "B.SilkS")
		)
		(fp_line
			(start -0.7874 -0.4064)
			(end -0.7874 0.4064)
			(stroke
				(width 0.1524)
				(type default)
			)
			(layer "B.SilkS")
		)
		(fp_line
			(start 0.7874 0.4064)
			(end 0.7874 -0.4064)
			(stroke
				(width 0.1524)
				(type default)
			)
			(layer "B.SilkS")
		)
		(fp_line
			(start -0.7874 0.4064)
			(end 0.7874 0.4064)
			(stroke
				(width 0.1524)
				(type default)
			)
			(layer "B.SilkS")
		)
		(fp_line
			(start 0.67945 -0.305054)
			(end 0.12065 -0.305054)
			(stroke
				(width 0.1)
				(type default)
			)
			(layer "B.Fab")
		)
		(fp_line
			(start 0.12065 -0.305054)
			(end 0.12065 -0.2794)
			(stroke
				(width 0.1)
				(type default)
			)
			(layer "B.Fab")
		)
		(fp_line
			(start -0.12065 -0.3048)
			(end -0.67945 -0.3048)
			(stroke
				(width 0.1)
				(type default)
			)
			(layer "B.Fab")
		)
		(fp_line
			(start -0.67945 -0.3048)
			(end -0.67945 0.3048)
			(stroke
				(width 0.1)
				(type default)
			)
			(layer "B.Fab")
		)
		(fp_line
			(start 0.12065 -0.2794)
			(end -0.12065 -0.2794)
			(stroke
				(width 0.1)
				(type default)
			)
			(layer "B.Fab")
		)
		(fp_line
			(start -0.12065 -0.2794)
			(end -0.12065 -0.3048)
			(stroke
				(width 0.1)
				(type default)
			)
			(layer "B.Fab")
		)
		(fp_line
			(start 0.12065 0.2794)
			(end 0.12065 0.3048)
			(stroke
				(width 0.1)
				(type default)
			)
			(layer "B.Fab")
		)
		(fp_line
			(start -0.120396 0.2794)
			(end 0.12065 0.2794)
			(stroke
				(width 0.1)
				(type default)
			)
			(layer "B.Fab")
		)
		(fp_line
			(start 0.67945 0.3048)
			(end 0.67945 -0.305054)
			(stroke
				(width 0.1)
				(type default)
			)
			(layer "B.Fab")
		)
		(fp_line
			(start 0.12065 0.3048)
			(end 0.67945 0.3048)
			(stroke
				(width 0.1)
				(type default)
			)
			(layer "B.Fab")
		)
		(fp_line
			(start -0.120396 0.3048)
			(end -0.120396 0.2794)
			(stroke
				(width 0.1)
				(type default)
			)
			(layer "B.Fab")
		)
		(fp_line
			(start -0.67945 0.3048)
			(end -0.120396 0.3048)
			(stroke
				(width 0.1)
				(type default)
			)
			(layer "B.Fab")
		)
		(pad "1" smd circle
			(at 0.40005 0 270)
			(size 0 0)
			(layers "B.Cu" "B.Mask" "B.Paste")
			(net "P0V9_CPU1_RT0_2A")
		)
		(pad "2" smd circle
			(at -0.40005 0 270)
			(size 0 0)
			(layers "B.Cu" "B.Mask" "B.Paste")
			(net "GND")
		)
	)
	(footprint ""
		(layer "B.Cu")
		(at 122.468386 -261.04723)
		(property "Reference" "C3917"
			(at 0 0 0)
			(layer "B.SilkS")
			(hide yes)
			(effects
				(font
					(size 1.27 1.27)
				)
				(justify mirror)
			)
		)
		(property "Value" ""
			(at 0 0 0)
			(layer "B.Fab")
			(effects
				(font
					(size 1.27 1.27)
				)
				(justify mirror)
			)
		)
		(duplicate_pad_numbers_are_jumpers no)
		(fp_line
			(start -0.7874 -0.4064)
			(end -0.7874 0.4064)
			(stroke
				(width 0.1524)
				(type default)
			)
			(layer "B.SilkS")
		)
		(fp_line
			(start -0.7874 0.4064)
			(end 0.7874 0.4064)
			(stroke
				(width 0.1524)
				(type default)
			)
			(layer "B.SilkS")
		)
		(fp_line
			(start 0.7874 -0.4064)
			(end -0.7874 -0.4064)
			(stroke
				(width 0.1524)
				(type default)
			)
			(layer "B.SilkS")
		)
		(fp_line
			(start 0.7874 0.4064)
			(end 0.7874 -0.4064)
			(stroke
				(width 0.1524)
				(type default)
			)
			(layer "B.SilkS")
		)
		(fp_line
			(start -0.67945 -0.3048)
			(end -0.67945 0.3048)
			(stroke
				(width 0.1)
				(type default)
			)
			(layer "B.Fab")
		)
		(fp_line
			(start -0.67945 0.3048)
			(end -0.120396 0.3048)
			(stroke
				(width 0.1)
				(type default)
			)
			(layer "B.Fab")
		)
		(fp_line
			(start -0.12065 -0.3048)
			(end -0.67945 -0.3048)
			(stroke
				(width 0.1)
				(type default)
			)
			(layer "B.Fab")
		)
		(fp_line
			(start -0.12065 -0.2794)
			(end -0.12065 -0.3048)
			(stroke
				(width 0.1)
				(type default)
			)
			(layer "B.Fab")
		)
		(fp_line
			(start -0.120396 0.2794)
			(end 0.12065 0.2794)
			(stroke
				(width 0.1)
				(type default)
			)
			(layer "B.Fab")
		)
		(fp_line
			(start -0.120396 0.3048)
			(end -0.120396 0.2794)
			(stroke
				(width 0.1)
				(type default)
			)
			(layer "B.Fab")
		)
		(fp_line
			(start 0.12065 -0.305054)
			(end 0.12065 -0.2794)
			(stroke
				(width 0.1)
				(type default)
			)
			(layer "B.Fab")
		)
		(fp_line
			(start 0.12065 -0.2794)
			(end -0.12065 -0.2794)
			(stroke
				(width 0.1)
				(type default)
			)
			(layer "B.Fab")
		)
		(fp_line
			(start 0.12065 0.2794)
			(end 0.12065 0.3048)
			(stroke
				(width 0.1)
				(type default)
			)
			(layer "B.Fab")
		)
		(fp_line
			(start 0.12065 0.3048)
			(end 0.67945 0.3048)
			(stroke
				(width 0.1)
				(type default)
			)
			(layer "B.Fab")
		)
		(fp_line
			(start 0.67945 -0.305054)
			(end 0.12065 -0.305054)
			(stroke
				(width 0.1)
				(type default)
			)
			(layer "B.Fab")
		)
		(fp_line
			(start 0.67945 0.3048)
			(end 0.67945 -0.305054)
			(stroke
				(width 0.1)
				(type default)
			)
			(layer "B.Fab")
		)
		(pad "1" smd circle
			(at 0.40005 0 180)
			(size 0 0)
			(layers "B.Cu" "B.Mask" "B.Paste")
			(net "PVDDCR_SOC_P1")
		)
		(pad "2" smd circle
			(at -0.40005 0 180)
			(size 0 0)
			(layers "B.Cu" "B.Mask" "B.Paste")
			(net "GND")
		)
	)
)
